(kicad_pcb
	(version 20260206)
	(generator "pcbnew")
	(generator_version "10.0")
	(general
		(thickness 1.6)
		(legacy_teardrops no)
	)
	(paper "A4")
	(title_block
		(title "04192023_DAF0TMB3IC0_F0TG_MB_C_brd_V02_OCP.brd")
		(comment 1 "Grand Teton / footprints 615-621 of 8354")
	)
	(layers
		(0 "F.Cu" signal "TOP")
		(4 "In1.Cu" signal "GND")
		(6 "In2.Cu" signal "IN1")
		(8 "In3.Cu" signal "GND1")
		(10 "In4.Cu" signal "IN2")
		(12 "In5.Cu" signal "GND2")
		(14 "In6.Cu" signal "IN3")
		(16 "In7.Cu" signal "GND3")
		(18 "In8.Cu" signal "VCC")
		(20 "In9.Cu" signal "VCC1")
		(22 "In10.Cu" signal "GND4")
		(24 "In11.Cu" signal "IN4")
		(26 "In12.Cu" signal "GND5")
		(28 "In13.Cu" signal "IN5")
		(30 "In14.Cu" signal "GND6")
		(32 "In15.Cu" signal "IN6")
		(34 "In16.Cu" signal "GND7")
		(2 "B.Cu" signal "BOTTOM")
		(9 "F.Adhes" user "F.Adhesive")
		(11 "B.Adhes" user "B.Adhesive")
		(13 "F.Paste" user "Package Geometry/Pastemask Top")
		(15 "B.Paste" user "Package Geometry/Pastemask Bottom")
		(5 "F.SilkS" user "Ref Des/Silkscreen Top")
		(7 "B.SilkS" user "Ref Des/Silkscreen Bottom")
		(1 "F.Mask" user "Board Geometry/Soldermask Top")
		(3 "B.Mask" user "Board Geometry/Soldermask Bottom")
		(17 "Dwgs.User" user "User.Drawings")
		(19 "Cmts.User" user "User.Comments")
		(21 "Eco1.User" user "User.Eco1")
		(23 "Eco2.User" user "User.Eco2")
		(25 "Edge.Cuts" user "Board Geometry/Outline")
		(27 "Margin" user)
		(31 "F.CrtYd" user "Package Geometry/Place Bound Top")
		(29 "B.CrtYd" user "Package Geometry/Place Bound Bottom")
		(35 "F.Fab" user "Ref Des/Assembly Top")
		(33 "B.Fab" user "Ref Des/Assembly Bottom")
	)
	(footprint ""
		(layer "F.Cu")
		(at 188.087 -137.632948 -90)
		(property "Reference" "R1551"
			(at 0 0 270)
			(layer "F.SilkS")
			(hide yes)
			(effects
				(font
					(size 1.27 1.27)
				)
			)
		)
		(property "Value" ""
			(at 0 0 270)
			(layer "F.Fab")
			(effects
				(font
					(size 1.27 1.27)
				)
			)
		)
		(duplicate_pad_numbers_are_jumpers no)
		(fp_line
			(start -0.7874 0.4064)
			(end -0.7874 -0.4064)
			(stroke
				(width 0.1524)
				(type default)
			)
			(layer "F.SilkS")
		)
		(fp_line
			(start 0.7874 0.4064)
			(end -0.7874 0.4064)
			(stroke
				(width 0.1524)
				(type default)
			)
			(layer "F.SilkS")
		)
		(fp_line
			(start -0.7874 -0.4064)
			(end 0.7874 -0.4064)
			(stroke
				(width 0.1524)
				(type default)
			)
			(layer "F.SilkS")
		)
		(fp_line
			(start 0.7874 -0.4064)
			(end 0.7874 0.4064)
			(stroke
				(width 0.1524)
				(type default)
			)
			(layer "F.SilkS")
		)
		(fp_line
			(start -0.67945 0.3048)
			(end -0.67945 -0.305054)
			(stroke
				(width 0.1)
				(type default)
			)
			(layer "F.Fab")
		)
		(fp_line
			(start -0.12065 0.3048)
			(end -0.67945 0.3048)
			(stroke
				(width 0.1)
				(type default)
			)
			(layer "F.Fab")
		)
		(fp_line
			(start 0.120396 0.3048)
			(end 0.120396 0.2794)
			(stroke
				(width 0.1)
				(type default)
			)
			(layer "F.Fab")
		)
		(fp_line
			(start 0.67945 0.3048)
			(end 0.120396 0.3048)
			(stroke
				(width 0.1)
				(type default)
			)
			(layer "F.Fab")
		)
		(fp_line
			(start -0.12065 0.2794)
			(end -0.12065 0.3048)
			(stroke
				(width 0.1)
				(type default)
			)
			(layer "F.Fab")
		)
		(fp_line
			(start 0.120396 0.2794)
			(end -0.12065 0.2794)
			(stroke
				(width 0.1)
				(type default)
			)
			(layer "F.Fab")
		)
		(fp_line
			(start -0.12065 -0.2794)
			(end 0.12065 -0.2794)
			(stroke
				(width 0.1)
				(type default)
			)
			(layer "F.Fab")
		)
		(fp_line
			(start 0.12065 -0.2794)
			(end 0.12065 -0.3048)
			(stroke
				(width 0.1)
				(type default)
			)
			(layer "F.Fab")
		)
		(fp_line
			(start 0.12065 -0.3048)
			(end 0.67945 -0.3048)
			(stroke
				(width 0.1)
				(type default)
			)
			(layer "F.Fab")
		)
		(fp_line
			(start 0.67945 -0.3048)
			(end 0.67945 0.3048)
			(stroke
				(width 0.1)
				(type default)
			)
			(layer "F.Fab")
		)
		(fp_line
			(start -0.67945 -0.305054)
			(end -0.12065 -0.305054)
			(stroke
				(width 0.1)
				(type default)
			)
			(layer "F.Fab")
		)
		(fp_line
			(start -0.12065 -0.305054)
			(end -0.12065 -0.2794)
			(stroke
				(width 0.1)
				(type default)
			)
			(layer "F.Fab")
		)
		(pad "1" smd circle
			(at -0.40005 0 270)
			(size 0 0)
			(layers "F.Cu" "F.Mask" "F.Paste")
			(net "ESPI_CPU0_R1_D2")
		)
		(pad "2" smd circle
			(at 0.40005 0 270)
			(size 0 0)
			(layers "F.Cu" "F.Mask" "F.Paste")
			(net "ESPI_CPU0_D2")
		)
	)
	(footprint ""
		(layer "F.Cu")
		(at 271.092676 -118.618)
		(property "Reference" "R1312"
			(at 0 0 0)
			(layer "F.SilkS")
			(hide yes)
			(effects
				(font
					(size 1.27 1.27)
				)
			)
		)
		(property "Value" ""
			(at 0 0 0)
			(layer "F.Fab")
			(effects
				(font
					(size 1.27 1.27)
				)
			)
		)
		(duplicate_pad_numbers_are_jumpers no)
		(fp_line
			(start -0.7874 -0.4064)
			(end 0.7874 -0.4064)
			(stroke
				(width 0.1524)
				(type default)
			)
			(layer "F.SilkS")
		)
		(fp_line
			(start -0.7874 0.4064)
			(end -0.7874 -0.4064)
			(stroke
				(width 0.1524)
				(type default)
			)
			(layer "F.SilkS")
		)
		(fp_line
			(start 0.7874 -0.4064)
			(end 0.7874 0.4064)
			(stroke
				(width 0.1524)
				(type default)
			)
			(layer "F.SilkS")
		)
		(fp_line
			(start 0.7874 0.4064)
			(end -0.7874 0.4064)
			(stroke
				(width 0.1524)
				(type default)
			)
			(layer "F.SilkS")
		)
		(fp_line
			(start -0.67945 -0.305054)
			(end -0.12065 -0.305054)
			(stroke
				(width 0.1)
				(type default)
			)
			(layer "F.Fab")
		)
		(fp_line
			(start -0.67945 0.3048)
			(end -0.67945 -0.305054)
			(stroke
				(width 0.1)
				(type default)
			)
			(layer "F.Fab")
		)
		(fp_line
			(start -0.12065 -0.305054)
			(end -0.12065 -0.2794)
			(stroke
				(width 0.1)
				(type default)
			)
			(layer "F.Fab")
		)
		(fp_line
			(start -0.12065 -0.2794)
			(end 0.12065 -0.2794)
			(stroke
				(width 0.1)
				(type default)
			)
			(layer "F.Fab")
		)
		(fp_line
			(start -0.12065 0.2794)
			(end -0.12065 0.3048)
			(stroke
				(width 0.1)
				(type default)
			)
			(layer "F.Fab")
		)
		(fp_line
			(start -0.12065 0.3048)
			(end -0.67945 0.3048)
			(stroke
				(width 0.1)
				(type default)
			)
			(layer "F.Fab")
		)
		(fp_line
			(start 0.120396 0.2794)
			(end -0.12065 0.2794)
			(stroke
				(width 0.1)
				(type default)
			)
			(layer "F.Fab")
		)
		(fp_line
			(start 0.120396 0.3048)
			(end 0.120396 0.2794)
			(stroke
				(width 0.1)
				(type default)
			)
			(layer "F.Fab")
		)
		(fp_line
			(start 0.12065 -0.3048)
			(end 0.67945 -0.3048)
			(stroke
				(width 0.1)
				(type default)
			)
			(layer "F.Fab")
		)
		(fp_line
			(start 0.12065 -0.2794)
			(end 0.12065 -0.3048)
			(stroke
				(width 0.1)
				(type default)
			)
			(layer "F.Fab")
		)
		(fp_line
			(start 0.67945 -0.3048)
			(end 0.67945 0.3048)
			(stroke
				(width 0.1)
				(type default)
			)
			(layer "F.Fab")
		)
		(fp_line
			(start 0.67945 0.3048)
			(end 0.120396 0.3048)
			(stroke
				(width 0.1)
				(type default)
			)
			(layer "F.Fab")
		)
		(pad "1" smd circle
			(at -0.40005 0)
			(size 0 0)
			(layers "F.Cu" "F.Mask" "F.Paste")
			(net "SMB_ADC_SDA")
		)
		(pad "2" smd circle
			(at 0.40005 0)
			(size 0 0)
			(layers "F.Cu" "F.Mask" "F.Paste")
			(net "SMB_ADC_SDA_R")
		)
	)
	(footprint ""
		(layer "F.Cu")
		(at 254 -38.683946 180)
		(property "Reference" "R3976"
			(at 0 0 180)
			(layer "F.SilkS")
			(hide yes)
			(effects
				(font
					(size 1.27 1.27)
				)
			)
		)
		(property "Value" ""
			(at 0 0 180)
			(layer "F.Fab")
			(effects
				(font
					(size 1.27 1.27)
				)
			)
		)
		(duplicate_pad_numbers_are_jumpers no)
		(fp_line
			(start 0.7874 0.4064)
			(end -0.7874 0.4064)
			(stroke
				(width 0.1524)
				(type default)
			)
			(layer "F.SilkS")
		)
		(fp_line
			(start 0.7874 -0.4064)
			(end 0.7874 0.4064)
			(stroke
				(width 0.1524)
				(type default)
			)
			(layer "F.SilkS")
		)
		(fp_line
			(start -0.7874 0.4064)
			(end -0.7874 -0.4064)
			(stroke
				(width 0.1524)
				(type default)
			)
			(layer "F.SilkS")
		)
		(fp_line
			(start -0.7874 -0.4064)
			(end 0.7874 -0.4064)
			(stroke
				(width 0.1524)
				(type default)
			)
			(layer "F.SilkS")
		)
		(fp_line
			(start 0.67945 0.3048)
			(end 0.120396 0.3048)
			(stroke
				(width 0.1)
				(type default)
			)
			(layer "F.Fab")
		)
		(fp_line
			(start 0.67945 -0.3048)
			(end 0.67945 0.3048)
			(stroke
				(width 0.1)
				(type default)
			)
			(layer "F.Fab")
		)
		(fp_line
			(start 0.12065 -0.2794)
			(end 0.12065 -0.3048)
			(stroke
				(width 0.1)
				(type default)
			)
			(layer "F.Fab")
		)
		(fp_line
			(start 0.12065 -0.3048)
			(end 0.67945 -0.3048)
			(stroke
				(width 0.1)
				(type default)
			)
			(layer "F.Fab")
		)
		(fp_line
			(start 0.120396 0.3048)
			(end 0.120396 0.2794)
			(stroke
				(width 0.1)
				(type default)
			)
			(layer "F.Fab")
		)
		(fp_line
			(start 0.120396 0.2794)
			(end -0.12065 0.2794)
			(stroke
				(width 0.1)
				(type default)
			)
			(layer "F.Fab")
		)
		(fp_line
			(start -0.12065 0.3048)
			(end -0.67945 0.3048)
			(stroke
				(width 0.1)
				(type default)
			)
			(layer "F.Fab")
		)
		(fp_line
			(start -0.12065 0.2794)
			(end -0.12065 0.3048)
			(stroke
				(width 0.1)
				(type default)
			)
			(layer "F.Fab")
		)
		(fp_line
			(start -0.12065 -0.2794)
			(end 0.12065 -0.2794)
			(stroke
				(width 0.1)
				(type default)
			)
			(layer "F.Fab")
		)
		(fp_line
			(start -0.12065 -0.305054)
			(end -0.12065 -0.2794)
			(stroke
				(width 0.1)
				(type default)
			)
			(layer "F.Fab")
		)
		(fp_line
			(start -0.67945 0.3048)
			(end -0.67945 -0.305054)
			(stroke
				(width 0.1)
				(type default)
			)
			(layer "F.Fab")
		)
		(fp_line
			(start -0.67945 -0.305054)
			(end -0.12065 -0.305054)
			(stroke
				(width 0.1)
				(type default)
			)
			(layer "F.Fab")
		)
		(pad "1" smd circle
			(at -0.40005 0 180)
			(size 0 0)
			(layers "F.Cu" "F.Mask" "F.Paste")
			(net "P3V3_AUX")
		)
		(pad "2" smd circle
			(at 0.40005 0 180)
			(size 0 0)
			(layers "F.Cu" "F.Mask" "F.Paste")
			(net "P12V_E1S_FAULT_0")
		)
	)
	(footprint ""
		(layer "F.Cu")
		(at 189.865 -96.103948 90)
		(property "Reference" "R6073"
			(at 0 0 90)
			(layer "F.SilkS")
			(hide yes)
			(effects
				(font
					(size 1.27 1.27)
				)
			)
		)
		(property "Value" ""
			(at 0 0 90)
			(layer "F.Fab")
			(effects
				(font
					(size 1.27 1.27)
				)
			)
		)
		(duplicate_pad_numbers_are_jumpers no)
		(fp_line
			(start 0.7874 -0.4064)
			(end 0.7874 0.4064)
			(stroke
				(width 0.1524)
				(type default)
			)
			(layer "F.SilkS")
		)
		(fp_line
			(start -0.7874 -0.4064)
			(end 0.7874 -0.4064)
			(stroke
				(width 0.1524)
				(type default)
			)
			(layer "F.SilkS")
		)
		(fp_line
			(start 0.7874 0.4064)
			(end -0.7874 0.4064)
			(stroke
				(width 0.1524)
				(type default)
			)
			(layer "F.SilkS")
		)
		(fp_line
			(start -0.7874 0.4064)
			(end -0.7874 -0.4064)
			(stroke
				(width 0.1524)
				(type default)
			)
			(layer "F.SilkS")
		)
		(fp_line
			(start -0.12065 -0.305054)
			(end -0.12065 -0.2794)
			(stroke
				(width 0.1)
				(type default)
			)
			(layer "F.Fab")
		)
		(fp_line
			(start -0.67945 -0.305054)
			(end -0.12065 -0.305054)
			(stroke
				(width 0.1)
				(type default)
			)
			(layer "F.Fab")
		)
		(fp_line
			(start 0.67945 -0.3048)
			(end 0.67945 0.3048)
			(stroke
				(width 0.1)
				(type default)
			)
			(layer "F.Fab")
		)
		(fp_line
			(start 0.12065 -0.3048)
			(end 0.67945 -0.3048)
			(stroke
				(width 0.1)
				(type default)
			)
			(layer "F.Fab")
		)
		(fp_line
			(start 0.12065 -0.2794)
			(end 0.12065 -0.3048)
			(stroke
				(width 0.1)
				(type default)
			)
			(layer "F.Fab")
		)
		(fp_line
			(start -0.12065 -0.2794)
			(end 0.12065 -0.2794)
			(stroke
				(width 0.1)
				(type default)
			)
			(layer "F.Fab")
		)
		(fp_line
			(start 0.120396 0.2794)
			(end -0.12065 0.2794)
			(stroke
				(width 0.1)
				(type default)
			)
			(layer "F.Fab")
		)
		(fp_line
			(start -0.12065 0.2794)
			(end -0.12065 0.3048)
			(stroke
				(width 0.1)
				(type default)
			)
			(layer "F.Fab")
		)
		(fp_line
			(start 0.67945 0.3048)
			(end 0.120396 0.3048)
			(stroke
				(width 0.1)
				(type default)
			)
			(layer "F.Fab")
		)
		(fp_line
			(start 0.120396 0.3048)
			(end 0.120396 0.2794)
			(stroke
				(width 0.1)
				(type default)
			)
			(layer "F.Fab")
		)
		(fp_line
			(start -0.12065 0.3048)
			(end -0.67945 0.3048)
			(stroke
				(width 0.1)
				(type default)
			)
			(layer "F.Fab")
		)
		(fp_line
			(start -0.67945 0.3048)
			(end -0.67945 -0.305054)
			(stroke
				(width 0.1)
				(type default)
			)
			(layer "F.Fab")
		)
		(pad "1" smd circle
			(at -0.40005 0 90)
			(size 0 0)
			(layers "F.Cu" "F.Mask" "F.Paste")
			(net "FM_PDB_BUF_EN_R_N")
		)
		(pad "2" smd circle
			(at 0.40005 0 90)
			(size 0 0)
			(layers "F.Cu" "F.Mask" "F.Paste")
			(net "FM_PDB_BUF_EN_N")
		)
	)
	(footprint ""
		(layer "F.Cu")
		(at 233.2228 -287.0708)
		(property "Reference" "PC6905"
			(at 0 0 0)
			(layer "F.SilkS")
			(hide yes)
			(effects
				(font
					(size 1.27 1.27)
				)
			)
		)
		(property "Value" ""
			(at 0 0 0)
			(layer "F.Fab")
			(effects
				(font
					(size 1.27 1.27)
				)
			)
		)
		(duplicate_pad_numbers_are_jumpers no)
		(fp_line
			(start -1.524 -0.762)
			(end 1.524 -0.762)
			(stroke
				(width 0.1524)
				(type default)
			)
			(layer "F.SilkS")
		)
		(fp_line
			(start -1.524 0.762)
			(end -1.524 -0.762)
			(stroke
				(width 0.1524)
				(type default)
			)
			(layer "F.SilkS")
		)
		(fp_line
			(start 1.524 -0.762)
			(end 1.524 0.762)
			(stroke
				(width 0.1524)
				(type default)
			)
			(layer "F.SilkS")
		)
		(fp_line
			(start 1.524 0.762)
			(end -1.524 0.762)
			(stroke
				(width 0.1524)
				(type default)
			)
			(layer "F.SilkS")
		)
		(fp_line
			(start -1.1049 -0.724916)
			(end -1.1049 0.724916)
			(stroke
				(width 0.1)
				(type default)
			)
			(layer "F.Fab")
		)
		(fp_line
			(start -1.1049 0.724916)
			(end 1.1049 0.724916)
			(stroke
				(width 0.1)
				(type default)
			)
			(layer "F.Fab")
		)
		(fp_line
			(start 1.1049 -0.724916)
			(end -1.1049 -0.724916)
			(stroke
				(width 0.1)
				(type default)
			)
			(layer "F.Fab")
		)
		(fp_line
			(start 1.1049 0.724916)
			(end 1.1049 -0.724916)
			(stroke
				(width 0.1)
				(type default)
			)
			(layer "F.Fab")
		)
		(pad "1" smd rect
			(at -0.889 0 180)
			(size 1.016 1.27)
			(layers "F.Cu" "F.Mask" "F.Paste")
			(net "SW_P12V_AUX_P1V8_RETIMER_CPU1_FLT")
		)
		(pad "2" smd rect
			(at 0.889 0 180)
			(size 1.016 1.27)
			(layers "F.Cu" "F.Mask" "F.Paste")
			(net "GND")
		)
	)
	(footprint ""
		(layer "F.Cu")
		(at 473.635324 -437.43753 180)
		(property "Reference" "DB7"
			(at 3.42519 1.965452 0)
			(unlocked yes)
			(layer "F.SilkS")
			(effects
				(font
					(size 0.7874 0.5842)
					(thickness 0.1524)
				)
				(justify left)
			)
		)
		(property "Value" ""
			(at 0 0 180)
			(layer "F.Fab")
			(effects
				(font
					(size 1.27 1.27)
				)
			)
		)
		(duplicate_pad_numbers_are_jumpers no)
		(fp_line
			(start 3.330702 -4.771136)
			(end 0 4.011168)
			(stroke
				(width 0.1524)
				(type default)
			)
			(layer "F.SilkS")
		)
		(fp_line
			(start 0 4.011168)
			(end -3.330702 -4.771136)
			(stroke
				(width 0.1524)
				(type default)
			)
			(layer "F.SilkS")
		)
		(fp_line
			(start -3.330702 -4.771136)
			(end 3.330702 -4.771136)
			(stroke
				(width 0.1524)
				(type default)
			)
			(layer "F.SilkS")
		)
		(fp_line
			(start 3.330702 -4.771136)
			(end 0 4.011168)
			(stroke
				(width 0.1)
				(type default)
			)
			(layer "F.Fab")
		)
		(fp_line
			(start 0 4.011168)
			(end -3.330702 -4.771136)
			(stroke
				(width 0.1)
				(type default)
			)
			(layer "F.Fab")
		)
		(fp_line
			(start -3.330702 -4.771136)
			(end 3.330702 -4.771136)
			(stroke
				(width 0.1)
				(type default)
			)
			(layer "F.Fab")
		)
		(pad "1" thru_hole circle
			(at 0 0 180)
			(size 2.159 2.159)
			(drill 1.7018)
			(layers "*.Cu" "*.Mask")
			(remove_unused_layers no)
			(net "T1_GND")
			(clearance 0.0254)
			(thermal_gap 0.0254)
		)
		(pad "2" thru_hole circle
			(at -1.27 -3.348736 180)
			(size 2.159 2.159)
			(drill 1.7018)
			(layers "*.Cu" "*.Mask")
			(remove_unused_layers no)
			(net "TDR_SE_50_OHM_TOP")
			(clearance 0.0254)
			(thermal_gap 0.0254)
		)
		(pad "3" thru_hole circle
			(at 1.27 -3.348736 180)
			(size 2.159 2.159)
			(drill 1.7018)
			(layers "*.Cu" "*.Mask")
			(remove_unused_layers no)
			(net "TDR_SE_50_OHM_TOP")
			(clearance 0.0254)
			(thermal_gap 0.0254)
		)
	)
	(footprint ""
		(layer "F.Cu")
		(at 378.85624 -151.393398 -90)
		(property "Reference" "PC583"
			(at 0 0 270)
			(layer "F.SilkS")
			(hide yes)
			(effects
				(font
					(size 1.27 1.27)
				)
			)
		)
		(property "Value" ""
			(at 0 0 270)
			(layer "F.Fab")
			(effects
				(font
					(size 1.27 1.27)
				)
			)
		)
		(duplicate_pad_numbers_are_jumpers no)
		(fp_line
			(start -0.7874 0.4064)
			(end -0.7874 -0.4064)
			(stroke
				(width 0.1524)
				(type default)
			)
			(layer "F.SilkS")
		)
		(fp_line
			(start 0.7874 0.4064)
			(end -0.7874 0.4064)
			(stroke
				(width 0.1524)
				(type default)
			)
			(layer "F.SilkS")
		)
		(fp_line
			(start -0.7874 -0.4064)
			(end 0.7874 -0.4064)
			(stroke
				(width 0.1524)
				(type default)
			)
			(layer "F.SilkS")
		)
		(fp_line
			(start 0.7874 -0.4064)
			(end 0.7874 0.4064)
			(stroke
				(width 0.1524)
				(type default)
			)
			(layer "F.SilkS")
		)
		(fp_line
			(start -0.67945 0.3048)
			(end -0.67945 -0.305054)
			(stroke
				(width 0.1)
				(type default)
			)
			(layer "F.Fab")
		)
		(fp_line
			(start -0.12065 0.3048)
			(end -0.67945 0.3048)
			(stroke
				(width 0.1)
				(type default)
			)
			(layer "F.Fab")
		)
		(fp_line
			(start 0.120396 0.3048)
			(end 0.120396 0.2794)
			(stroke
				(width 0.1)
				(type default)
			)
			(layer "F.Fab")
		)
		(fp_line
			(start 0.67945 0.3048)
			(end 0.120396 0.3048)
			(stroke
				(width 0.1)
				(type default)
			)
			(layer "F.Fab")
		)
		(fp_line
			(start -0.12065 0.2794)
			(end -0.12065 0.3048)
			(stroke
				(width 0.1)
				(type default)
			)
			(layer "F.Fab")
		)
		(fp_line
			(start 0.120396 0.2794)
			(end -0.12065 0.2794)
			(stroke
				(width 0.1)
				(type default)
			)
			(layer "F.Fab")
		)
		(fp_line
			(start -0.12065 -0.2794)
			(end 0.12065 -0.2794)
			(stroke
				(width 0.1)
				(type default)
			)
			(layer "F.Fab")
		)
		(fp_line
			(start 0.12065 -0.2794)
			(end 0.12065 -0.3048)
			(stroke
				(width 0.1)
				(type default)
			)
			(layer "F.Fab")
		)
		(fp_line
			(start 0.12065 -0.3048)
			(end 0.67945 -0.3048)
			(stroke
				(width 0.1)
				(type default)
			)
			(layer "F.Fab")
		)
		(fp_line
			(start 0.67945 -0.3048)
			(end 0.67945 0.3048)
			(stroke
				(width 0.1)
				(type default)
			)
			(layer "F.Fab")
		)
		(fp_line
			(start -0.67945 -0.305054)
			(end -0.12065 -0.305054)
			(stroke
				(width 0.1)
				(type default)
			)
			(layer "F.Fab")
		)
		(fp_line
			(start -0.12065 -0.305054)
			(end -0.12065 -0.2794)
			(stroke
				(width 0.1)
				(type default)
			)
			(layer "F.Fab")
		)
		(pad "1" smd circle
			(at -0.40005 0 270)
			(size 0 0)
			(layers "F.Cu" "F.Mask" "F.Paste")
			(net "P12V_AUX")
		)
		(pad "2" smd circle
			(at 0.40005 0 270)
			(size 0 0)
			(layers "F.Cu" "F.Mask" "F.Paste")
			(net "GND")
		)
	)
)
